(kicad_pcb
	(version 20260206)
	(generator "pcbnew")
	(generator_version "10.0")
	(general
		(thickness 1.6)
		(legacy_teardrops no)
	)
	(paper "A4")
	(title_block
		(title "Bryce Canyon_IOM_IOC_16318-2_OCP.brd")
		(comment 1 "Bryce Canyon / footprints 1194-1200 of 1605")
	)
	(layers
		(0 "F.Cu" signal "TOP")
		(4 "In1.Cu" signal "L2GND")
		(6 "In2.Cu" signal "L3")
		(8 "In3.Cu" signal "L4VCC")
		(10 "In4.Cu" signal "L5VCC")
		(12 "In5.Cu" signal "L6")
		(14 "In6.Cu" signal "L7GND")
		(2 "B.Cu" signal "BOTTOM")
		(9 "F.Adhes" user "F.Adhesive")
		(11 "B.Adhes" user "B.Adhesive")
		(13 "F.Paste" user "Package Geometry/Pastemask Top")
		(15 "B.Paste" user "Package Geometry/Pastemask Bottom")
		(5 "F.SilkS" user "Ref Des/Silkscreen Top")
		(7 "B.SilkS" user "Ref Des/Silkscreen Bottom")
		(1 "F.Mask" user "Board Geometry/Soldermask Top")
		(3 "B.Mask" user "Board Geometry/Soldermask Bottom")
		(17 "Dwgs.User" user "User.Drawings")
		(19 "Cmts.User" user "User.Comments")
		(21 "Eco1.User" user "User.Eco1")
		(23 "Eco2.User" user "User.Eco2")
		(25 "Edge.Cuts" user "Board Geometry/Outline")
		(27 "Margin" user)
		(31 "F.CrtYd" user "Package Geometry/Place Bound Top")
		(29 "B.CrtYd" user "Package Geometry/Place Bound Bottom")
		(35 "F.Fab" user "Ref Des/Assembly Top")
		(33 "B.Fab" user "Ref Des/Assembly Bottom")
	)
	(footprint ""
		(layer "B.Cu")
		(at 204.778864 -52.33543 -90)
		(property "Reference" "C341"
			(at 0 0 90)
			(layer "B.SilkS")
			(hide yes)
			(effects
				(font
					(size 1.27 1.27)
				)
				(justify mirror)
			)
		)
		(property "Value" "SCD1U6D3V1KX-GP"
			(at 2.8321 -1.7399 270)
			(unlocked yes)
			(layer "B.Fab")
			(hide yes)
			(effects
				(font
					(size 1.016 1.016)
					(thickness 0.1524)
				)
				(justify mirror)
			)
		)
		(property "Device Type" "C0201H13"
			(at 2.8321 -3.2639 270)
			(unlocked yes)
			(layer "B.Fab")
			(hide yes)
			(effects
				(font
					(size 1.016 1.016)
					(thickness 0.1524)
				)
				(justify mirror)
			)
		)
		(duplicate_pad_numbers_are_jumpers no)
		(fp_rect
			(start 0.2794 0.6477)
			(end -0.2794 -0.6477)
			(stroke
				(width 0)
				(type default)
			)
			(fill no)
			(layer "B.CrtYd")
		)
		(fp_rect
			(start 0.2794 0.6477)
			(end -0.2794 -0.6477)
			(stroke
				(width 0)
				(type default)
			)
			(fill no)
			(layer "B.Fab")
		)
		(pad "1" smd custom
			(at 0 -0.2794 90)
			(size 0.0762 0.0762)
			(layers "B.Cu" "B.Mask" "B.Paste")
			(net "SHELL_PLL_VDD")
			(options
				(clearance outline)
				(anchor circle)
			)
			(primitives
				(gr_poly
					(pts
						(arc
							(start 0.1524 0.127)
							(mid 0.137521 0.162921)
							(end 0.1016 0.1778)
						)
						(arc
							(start -0.1016 0.1778)
							(mid -0.137521 0.162921)
							(end -0.1524 0.127)
						)
						(arc
							(start -0.1524 -0.127)
							(mid -0.137521 -0.162921)
							(end -0.1016 -0.1778)
						)
						(arc
							(start 0.1016 -0.1778)
							(mid 0.137521 -0.162921)
							(end 0.1524 -0.127)
						)
					)
					(width 0)
					(fill yes)
				)
			)
		)
		(pad "2" smd custom
			(at 0 0.2794 90)
			(size 0.0762 0.0762)
			(layers "B.Cu" "B.Mask" "B.Paste")
			(net "GND")
			(options
				(clearance outline)
				(anchor circle)
			)
			(primitives
				(gr_poly
					(pts
						(arc
							(start 0.1524 0.127)
							(mid 0.137521 0.162921)
							(end 0.1016 0.1778)
						)
						(arc
							(start -0.1016 0.1778)
							(mid -0.137521 0.162921)
							(end -0.1524 0.127)
						)
						(arc
							(start -0.1524 -0.127)
							(mid -0.137521 -0.162921)
							(end -0.1016 -0.1778)
						)
						(arc
							(start 0.1016 -0.1778)
							(mid 0.137521 -0.162921)
							(end 0.1524 -0.127)
						)
					)
					(width 0)
					(fill yes)
				)
			)
		)
	)
	(footprint ""
		(layer "B.Cu")
		(at 51.74996 -158.69412 90)
		(property "Reference" "R192"
			(at 0 0 90)
			(layer "B.SilkS")
			(hide yes)
			(effects
				(font
					(size 1.27 1.27)
				)
				(justify mirror)
			)
		)
		(property "Value" "2K2R2F-GP"
			(at -0.064008 -3.993896 90)
			(unlocked yes)
			(layer "B.Fab")
			(hide yes)
			(effects
				(font
					(size 1.016 1.016)
					(thickness 0.1524)
				)
				(justify mirror)
			)
		)
		(property "Device Type" "R402H16"
			(at -0.064008 -5.517896 90)
			(unlocked yes)
			(layer "B.Fab")
			(hide yes)
			(effects
				(font
					(size 1.016 1.016)
					(thickness 0.1524)
				)
				(justify mirror)
			)
		)
		(duplicate_pad_numbers_are_jumpers no)
		(fp_line
			(start 0.508 -0.9398)
			(end 0.508 0.9398)
			(stroke
				(width 0.1524)
				(type default)
			)
			(layer "B.SilkS")
		)
		(fp_line
			(start -0.508 -0.9398)
			(end 0.508 -0.9398)
			(stroke
				(width 0.1524)
				(type default)
			)
			(layer "B.SilkS")
		)
		(fp_rect
			(start 0.508 0.9398)
			(end -0.508 -0.9398)
			(stroke
				(width 0)
				(type default)
			)
			(fill no)
			(layer "B.CrtYd")
		)
		(fp_rect
			(start 0.508 0.9398)
			(end -0.508 -0.9398)
			(stroke
				(width 0)
				(type default)
			)
			(fill no)
			(layer "B.Fab")
		)
		(pad "1" smd custom
			(at 0 -0.4445 270)
			(size 0.1397 0.1397)
			(layers "B.Cu" "B.Mask" "B.Paste")
			(net "I2C_MEZZ_OOB_SDA")
			(options
				(clearance outline)
				(anchor circle)
			)
			(primitives
				(gr_poly
					(pts
						(arc
							(start -0.1778 0.2794)
							(mid -0.249642 0.249642)
							(end -0.2794 0.1778)
						)
						(arc
							(start -0.2794 -0.1778)
							(mid -0.249642 -0.249642)
							(end -0.1778 -0.2794)
						)
						(arc
							(start 0.1778 -0.2794)
							(mid 0.249642 -0.249642)
							(end 0.2794 -0.1778)
						)
						(arc
							(start 0.2794 0.1778)
							(mid 0.249642 0.249642)
							(end 0.1778 0.2794)
						)
					)
					(width 0)
					(fill yes)
				)
			)
		)
		(pad "2" smd custom
			(at 0 0.4445 270)
			(size 0.1397 0.1397)
			(layers "B.Cu" "B.Mask" "B.Paste")
			(net "P3V3_STBY")
			(options
				(clearance outline)
				(anchor circle)
			)
			(primitives
				(gr_poly
					(pts
						(arc
							(start -0.1778 0.2794)
							(mid -0.249642 0.249642)
							(end -0.2794 0.1778)
						)
						(arc
							(start -0.2794 -0.1778)
							(mid -0.249642 -0.249642)
							(end -0.1778 -0.2794)
						)
						(arc
							(start 0.1778 -0.2794)
							(mid 0.249642 -0.249642)
							(end 0.2794 -0.1778)
						)
						(arc
							(start 0.2794 0.1778)
							(mid 0.249642 0.249642)
							(end 0.1778 0.2794)
						)
					)
					(width 0)
					(fill yes)
				)
			)
		)
	)
	(footprint ""
		(layer "B.Cu")
		(at 44.139866 -148.180298 -90)
		(property "Reference" "C55"
			(at 0 0 90)
			(layer "B.SilkS")
			(hide yes)
			(effects
				(font
					(size 1.27 1.27)
				)
				(justify mirror)
			)
		)
		(property "Value" "SCD1U16V2KX-3GP"
			(at -1.1811 -2.7051 270)
			(unlocked yes)
			(layer "B.Fab")
			(hide yes)
			(effects
				(font
					(size 1.016 1.016)
					(thickness 0.1524)
				)
				(justify mirror)
			)
		)
		(property "Device Type" "C402H22"
			(at -1.1811 -4.2291 270)
			(unlocked yes)
			(layer "B.Fab")
			(hide yes)
			(effects
				(font
					(size 1.016 1.016)
					(thickness 0.1524)
				)
				(justify mirror)
			)
		)
		(duplicate_pad_numbers_are_jumpers no)
		(fp_rect
			(start 0.4318 0.9525)
			(end -0.4318 -0.9525)
			(stroke
				(width 0)
				(type default)
			)
			(fill no)
			(layer "B.CrtYd")
		)
		(fp_rect
			(start 0.4318 0.9525)
			(end -0.4318 -0.9525)
			(stroke
				(width 0)
				(type default)
			)
			(fill no)
			(layer "B.Fab")
		)
		(pad "1" smd custom
			(at 0 -0.4445 90)
			(size 0.1524 0.1524)
			(layers "B.Cu" "B.Mask" "B.Paste")
			(net "GND")
			(options
				(clearance outline)
				(anchor circle)
			)
			(primitives
				(gr_poly
					(pts
						(arc
							(start 0.3048 0.2032)
							(mid 0.275042 0.275042)
							(end 0.2032 0.3048)
						)
						(arc
							(start -0.2032 0.3048)
							(mid -0.275042 0.275042)
							(end -0.3048 0.2032)
						)
						(arc
							(start -0.3048 -0.2032)
							(mid -0.275042 -0.275042)
							(end -0.2032 -0.3048)
						)
						(arc
							(start 0.2032 -0.3048)
							(mid 0.275042 -0.275042)
							(end 0.3048 -0.2032)
						)
					)
					(width 0)
					(fill yes)
				)
			)
		)
		(pad "2" smd custom
			(at 0 0.4445 90)
			(size 0.1524 0.1524)
			(layers "B.Cu" "B.Mask" "B.Paste")
			(net "DDR_VREF")
			(options
				(clearance outline)
				(anchor circle)
			)
			(primitives
				(gr_poly
					(pts
						(arc
							(start 0.3048 0.2032)
							(mid 0.275042 0.275042)
							(end 0.2032 0.3048)
						)
						(arc
							(start -0.2032 0.3048)
							(mid -0.275042 0.275042)
							(end -0.3048 0.2032)
						)
						(arc
							(start -0.3048 -0.2032)
							(mid -0.275042 -0.275042)
							(end -0.2032 -0.3048)
						)
						(arc
							(start 0.2032 -0.3048)
							(mid 0.275042 -0.275042)
							(end 0.3048 -0.2032)
						)
					)
					(width 0)
					(fill yes)
				)
			)
		)
	)
	(footprint ""
		(layer "B.Cu")
		(at 22.014942 -129.1082 180)
		(property "Reference" "R260"
			(at 0 0 0)
			(layer "B.SilkS")
			(hide yes)
			(effects
				(font
					(size 1.27 1.27)
				)
				(justify mirror)
			)
		)
		(property "Value" "120R2F-GP"
			(at -0.064008 -3.993896 180)
			(unlocked yes)
			(layer "B.Fab")
			(hide yes)
			(effects
				(font
					(size 1.016 1.016)
					(thickness 0.1524)
				)
				(justify mirror)
			)
		)
		(property "Device Type" "R402H16"
			(at -0.064008 -5.517896 180)
			(unlocked yes)
			(layer "B.Fab")
			(hide yes)
			(effects
				(font
					(size 1.016 1.016)
					(thickness 0.1524)
				)
				(justify mirror)
			)
		)
		(duplicate_pad_numbers_are_jumpers no)
		(fp_line
			(start 0.508 -0.9398)
			(end 0.508 0.9398)
			(stroke
				(width 0.1524)
				(type default)
			)
			(layer "B.SilkS")
		)
		(fp_line
			(start -0.508 -0.9398)
			(end 0.508 -0.9398)
			(stroke
				(width 0.1524)
				(type default)
			)
			(layer "B.SilkS")
		)
		(fp_rect
			(start 0.508 0.9398)
			(end -0.508 -0.9398)
			(stroke
				(width 0)
				(type default)
			)
			(fill no)
			(layer "B.CrtYd")
		)
		(fp_rect
			(start 0.508 0.9398)
			(end -0.508 -0.9398)
			(stroke
				(width 0)
				(type default)
			)
			(fill no)
			(layer "B.Fab")
		)
		(pad "1" smd custom
			(at 0 -0.4445)
			(size 0.1397 0.1397)
			(layers "B.Cu" "B.Mask" "B.Paste")
			(net "GND")
			(options
				(clearance outline)
				(anchor circle)
			)
			(primitives
				(gr_poly
					(pts
						(arc
							(start -0.1778 0.2794)
							(mid -0.249642 0.249642)
							(end -0.2794 0.1778)
						)
						(arc
							(start -0.2794 -0.1778)
							(mid -0.249642 -0.249642)
							(end -0.1778 -0.2794)
						)
						(arc
							(start 0.1778 -0.2794)
							(mid 0.249642 -0.249642)
							(end 0.2794 -0.1778)
						)
						(arc
							(start 0.2794 0.1778)
							(mid 0.249642 0.249642)
							(end 0.1778 0.2794)
						)
					)
					(width 0)
					(fill yes)
				)
			)
		)
		(pad "2" smd custom
			(at 0 0.4445)
			(size 0.1397 0.1397)
			(layers "B.Cu" "B.Mask" "B.Paste")
			(net "MEMA_13")
			(options
				(clearance outline)
				(anchor circle)
			)
			(primitives
				(gr_poly
					(pts
						(arc
							(start -0.1778 0.2794)
							(mid -0.249642 0.249642)
							(end -0.2794 0.1778)
						)
						(arc
							(start -0.2794 -0.1778)
							(mid -0.249642 -0.249642)
							(end -0.1778 -0.2794)
						)
						(arc
							(start 0.1778 -0.2794)
							(mid 0.249642 -0.249642)
							(end 0.2794 -0.1778)
						)
						(arc
							(start 0.2794 0.1778)
							(mid 0.249642 0.249642)
							(end 0.1778 0.2794)
						)
					)
					(width 0)
					(fill yes)
				)
			)
		)
	)
	(footprint ""
		(layer "B.Cu")
		(at 49.6316 -132.6642)
		(property "Reference" "C110"
			(at 0 0 0)
			(layer "B.SilkS")
			(hide yes)
			(effects
				(font
					(size 1.27 1.27)
				)
				(justify mirror)
			)
		)
		(property "Value" "SC1U16V3KX-5GP"
			(at 0 -2.8194 0)
			(unlocked yes)
			(layer "B.Fab")
			(hide yes)
			(effects
				(font
					(size 1.016 1.016)
					(thickness 0.1524)
				)
				(justify mirror)
			)
		)
		(property "Device Type" "C603H36"
			(at 0 -4.3434 0)
			(unlocked yes)
			(layer "B.Fab")
			(hide yes)
			(effects
				(font
					(size 1.016 1.016)
					(thickness 0.1524)
				)
				(justify mirror)
			)
		)
		(duplicate_pad_numbers_are_jumpers no)
		(fp_line
			(start -0.508 0)
			(end 0.508 0)
			(stroke
				(width 0.2032)
				(type default)
			)
			(layer "B.SilkS")
		)
		(fp_rect
			(start 0.5842 1.3335)
			(end -0.5842 -1.3335)
			(stroke
				(width 0)
				(type default)
			)
			(fill no)
			(layer "B.CrtYd")
		)
		(fp_rect
			(start 0.5842 1.3335)
			(end -0.5842 -1.3335)
			(stroke
				(width 0)
				(type default)
			)
			(fill no)
			(layer "B.Fab")
		)
		(pad "1" smd custom
			(at 0 -0.762 180)
			(size 0.2159 0.2159)
			(layers "B.Cu" "B.Mask" "B.Paste")
			(net "P1V15_STBY")
			(options
				(clearance outline)
				(anchor circle)
			)
			(primitives
				(gr_poly
					(pts
						(arc
							(start -0.3302 0.4318)
							(mid -0.402042 0.402042)
							(end -0.4318 0.3302)
						)
						(arc
							(start -0.4318 -0.3302)
							(mid -0.402042 -0.402042)
							(end -0.3302 -0.4318)
						)
						(arc
							(start 0.3302 -0.4318)
							(mid 0.402042 -0.402042)
							(end 0.4318 -0.3302)
						)
						(arc
							(start 0.4318 0.3302)
							(mid 0.402042 0.402042)
							(end 0.3302 0.4318)
						)
					)
					(width 0)
					(fill yes)
				)
			)
		)
		(pad "2" smd custom
			(at 0 0.762 180)
			(size 0.2159 0.2159)
			(layers "B.Cu" "B.Mask" "B.Paste")
			(net "GND")
			(options
				(clearance outline)
				(anchor circle)
			)
			(primitives
				(gr_poly
					(pts
						(arc
							(start -0.3302 0.4318)
							(mid -0.402042 0.402042)
							(end -0.4318 0.3302)
						)
						(arc
							(start -0.4318 -0.3302)
							(mid -0.402042 -0.402042)
							(end -0.3302 -0.4318)
						)
						(arc
							(start 0.3302 -0.4318)
							(mid 0.402042 -0.402042)
							(end 0.4318 -0.3302)
						)
						(arc
							(start 0.4318 0.3302)
							(mid 0.402042 0.402042)
							(end 0.3302 0.4318)
						)
					)
					(width 0)
					(fill yes)
				)
			)
		)
	)
	(footprint ""
		(layer "B.Cu")
		(at 12.11199 -139.579604 90)
		(property "Reference" "R234"
			(at 0 0 90)
			(layer "B.SilkS")
			(hide yes)
			(effects
				(font
					(size 1.27 1.27)
				)
				(justify mirror)
			)
		)
		(property "Value" "120R2F-GP"
			(at -0.064008 -3.993896 90)
			(unlocked yes)
			(layer "B.Fab")
			(hide yes)
			(effects
				(font
					(size 1.016 1.016)
					(thickness 0.1524)
				)
				(justify mirror)
			)
		)
		(property "Device Type" "R402H16"
			(at -0.064008 -5.517896 90)
			(unlocked yes)
			(layer "B.Fab")
			(hide yes)
			(effects
				(font
					(size 1.016 1.016)
					(thickness 0.1524)
				)
				(justify mirror)
			)
		)
		(duplicate_pad_numbers_are_jumpers no)
		(fp_line
			(start 0.508 -0.9398)
			(end 0.508 0.9398)
			(stroke
				(width 0.1524)
				(type default)
			)
			(layer "B.SilkS")
		)
		(fp_line
			(start -0.508 -0.9398)
			(end 0.508 -0.9398)
			(stroke
				(width 0.1524)
				(type default)
			)
			(layer "B.SilkS")
		)
		(fp_rect
			(start 0.508 0.9398)
			(end -0.508 -0.9398)
			(stroke
				(width 0)
				(type default)
			)
			(fill no)
			(layer "B.CrtYd")
		)
		(fp_rect
			(start 0.508 0.9398)
			(end -0.508 -0.9398)
			(stroke
				(width 0)
				(type default)
			)
			(fill no)
			(layer "B.Fab")
		)
		(pad "1" smd custom
			(at 0 -0.4445 270)
			(size 0.1397 0.1397)
			(layers "B.Cu" "B.Mask" "B.Paste")
			(net "MEMA_0")
			(options
				(clearance outline)
				(anchor circle)
			)
			(primitives
				(gr_poly
					(pts
						(arc
							(start -0.1778 0.2794)
							(mid -0.249642 0.249642)
							(end -0.2794 0.1778)
						)
						(arc
							(start -0.2794 -0.1778)
							(mid -0.249642 -0.249642)
							(end -0.1778 -0.2794)
						)
						(arc
							(start 0.1778 -0.2794)
							(mid 0.249642 -0.249642)
							(end 0.2794 -0.1778)
						)
						(arc
							(start 0.2794 0.1778)
							(mid 0.249642 0.249642)
							(end 0.1778 0.2794)
						)
					)
					(width 0)
					(fill yes)
				)
			)
		)
		(pad "2" smd custom
			(at 0 0.4445 270)
			(size 0.1397 0.1397)
			(layers "B.Cu" "B.Mask" "B.Paste")
			(net "P1V2_STBY")
			(options
				(clearance outline)
				(anchor circle)
			)
			(primitives
				(gr_poly
					(pts
						(arc
							(start -0.1778 0.2794)
							(mid -0.249642 0.249642)
							(end -0.2794 0.1778)
						)
						(arc
							(start -0.2794 -0.1778)
							(mid -0.249642 -0.249642)
							(end -0.1778 -0.2794)
						)
						(arc
							(start 0.1778 -0.2794)
							(mid 0.249642 -0.249642)
							(end 0.2794 -0.1778)
						)
						(arc
							(start 0.2794 0.1778)
							(mid 0.249642 0.249642)
							(end 0.1778 0.2794)
						)
					)
					(width 0)
					(fill yes)
				)
			)
		)
	)
	(footprint ""
		(layer "B.Cu")
		(at 204.4446 -69.5452 90)
		(property "Reference" "C379"
			(at 0 0 90)
			(layer "B.SilkS")
			(hide yes)
			(effects
				(font
					(size 1.27 1.27)
				)
				(justify mirror)
			)
		)
		(property "Value" "SCD1U6D3V1KX-GP"
			(at 2.8321 -1.7399 90)
			(unlocked yes)
			(layer "B.Fab")
			(hide yes)
			(effects
				(font
					(size 1.016 1.016)
					(thickness 0.1524)
				)
				(justify mirror)
			)
		)
		(property "Device Type" "C0201H13"
			(at 2.8321 -3.2639 90)
			(unlocked yes)
			(layer "B.Fab")
			(hide yes)
			(effects
				(font
					(size 1.016 1.016)
					(thickness 0.1524)
				)
				(justify mirror)
			)
		)
		(duplicate_pad_numbers_are_jumpers no)
		(fp_rect
			(start 0.2794 0.6477)
			(end -0.2794 -0.6477)
			(stroke
				(width 0)
				(type default)
			)
			(fill no)
			(layer "B.CrtYd")
		)
		(fp_rect
			(start 0.2794 0.6477)
			(end -0.2794 -0.6477)
			(stroke
				(width 0)
				(type default)
			)
			(fill no)
			(layer "B.Fab")
		)
		(pad "1" smd custom
			(at 0 -0.2794 270)
			(size 0.0762 0.0762)
			(layers "B.Cu" "B.Mask" "B.Paste")
			(net "SAS0_AVDD")
			(options
				(clearance outline)
				(anchor circle)
			)
			(primitives
				(gr_poly
					(pts
						(arc
							(start 0.1524 0.127)
							(mid 0.137521 0.162921)
							(end 0.1016 0.1778)
						)
						(arc
							(start -0.1016 0.1778)
							(mid -0.137521 0.162921)
							(end -0.1524 0.127)
						)
						(arc
							(start -0.1524 -0.127)
							(mid -0.137521 -0.162921)
							(end -0.1016 -0.1778)
						)
						(arc
							(start 0.1016 -0.1778)
							(mid 0.137521 -0.162921)
							(end 0.1524 -0.127)
						)
					)
					(width 0)
					(fill yes)
				)
			)
		)
		(pad "2" smd custom
			(at 0 0.2794 270)
			(size 0.0762 0.0762)
			(layers "B.Cu" "B.Mask" "B.Paste")
			(net "GND")
			(options
				(clearance outline)
				(anchor circle)
			)
			(primitives
				(gr_poly
					(pts
						(arc
							(start 0.1524 0.127)
							(mid 0.137521 0.162921)
							(end 0.1016 0.1778)
						)
						(arc
							(start -0.1016 0.1778)
							(mid -0.137521 0.162921)
							(end -0.1524 0.127)
						)
						(arc
							(start -0.1524 -0.127)
							(mid -0.137521 -0.162921)
							(end -0.1016 -0.1778)
						)
						(arc
							(start 0.1016 -0.1778)
							(mid 0.137521 -0.162921)
							(end 0.1524 -0.127)
						)
					)
					(width 0)
					(fill yes)
				)
			)
		)
	)
)
